(kicad_pcb
	(version 20260206)
	(generator "pcbnew")
	(generator_version "10.0")
	(general
		(thickness 1.6)
		(legacy_teardrops no)
	)
	(paper "A4")
	(title_block
		(title "01162023_DA0F0TEBIF0_F0T_Expander_BD_F_brd_V02_OCP.brd")
		(comment 1 "Grand Teton / footprints 6071-6077 of 9728")
	)
	(layers
		(0 "F.Cu" signal "TOP")
		(4 "In1.Cu" signal "GND")
		(6 "In2.Cu" signal "VCC")
		(8 "In3.Cu" signal "VCC1")
		(10 "In4.Cu" signal "GND1")
		(12 "In5.Cu" signal "IN1")
		(14 "In6.Cu" signal "GND2")
		(16 "In7.Cu" signal "IN2")
		(18 "In8.Cu" signal "GND3")
		(20 "In9.Cu" signal "IN3")
		(22 "In10.Cu" signal "GND4")
		(24 "In11.Cu" signal "IN4")
		(26 "In12.Cu" signal "GND5")
		(28 "In13.Cu" signal "IN5")
		(30 "In14.Cu" signal "GND6")
		(32 "In15.Cu" signal "IN6")
		(34 "In16.Cu" signal "GND7")
		(2 "B.Cu" signal "BOTTOM")
		(9 "F.Adhes" user "F.Adhesive")
		(11 "B.Adhes" user "B.Adhesive")
		(13 "F.Paste" user "Package Geometry/Pastemask Top")
		(15 "B.Paste" user "Package Geometry/Pastemask Bottom")
		(5 "F.SilkS" user "Ref Des/Silkscreen Top")
		(7 "B.SilkS" user "Ref Des/Silkscreen Bottom")
		(1 "F.Mask" user "Board Geometry/Soldermask Top")
		(3 "B.Mask" user "Board Geometry/Soldermask Bottom")
		(17 "Dwgs.User" user "User.Drawings")
		(19 "Cmts.User" user "User.Comments")
		(21 "Eco1.User" user "User.Eco1")
		(23 "Eco2.User" user "User.Eco2")
		(25 "Edge.Cuts" user "Board Geometry/Outline")
		(27 "Margin" user)
		(31 "F.CrtYd" user "Package Geometry/Place Bound Top")
		(29 "B.CrtYd" user "Package Geometry/Place Bound Bottom")
		(35 "F.Fab" user "Ref Des/Assembly Top")
		(33 "B.Fab" user "Ref Des/Assembly Bottom")
	)
	(footprint ""
		(layer "F.Cu")
		(at 411.047438 -86.424008)
		(property "Reference" "R6266"
			(at 0 0 0)
			(layer "F.SilkS")
			(hide yes)
			(effects
				(font
					(size 1.27 1.27)
				)
			)
		)
		(property "Value" ""
			(at 0 0 0)
			(layer "F.Fab")
			(effects
				(font
					(size 1.27 1.27)
				)
			)
		)
		(duplicate_pad_numbers_are_jumpers no)
		(fp_line
			(start -0.7874 -0.4064)
			(end 0.7874 -0.4064)
			(stroke
				(width 0.1524)
				(type default)
			)
			(layer "F.SilkS")
		)
		(fp_line
			(start -0.7874 0.4064)
			(end -0.7874 -0.4064)
			(stroke
				(width 0.1524)
				(type default)
			)
			(layer "F.SilkS")
		)
		(fp_line
			(start 0.7874 -0.4064)
			(end 0.7874 0.4064)
			(stroke
				(width 0.1524)
				(type default)
			)
			(layer "F.SilkS")
		)
		(fp_line
			(start 0.7874 0.4064)
			(end -0.7874 0.4064)
			(stroke
				(width 0.1524)
				(type default)
			)
			(layer "F.SilkS")
		)
		(fp_line
			(start -0.67945 -0.305054)
			(end -0.12065 -0.305054)
			(stroke
				(width 0.1)
				(type default)
			)
			(layer "F.Fab")
		)
		(fp_line
			(start -0.67945 0.3048)
			(end -0.67945 -0.305054)
			(stroke
				(width 0.1)
				(type default)
			)
			(layer "F.Fab")
		)
		(fp_line
			(start -0.12065 -0.305054)
			(end -0.12065 -0.2794)
			(stroke
				(width 0.1)
				(type default)
			)
			(layer "F.Fab")
		)
		(fp_line
			(start -0.12065 -0.2794)
			(end 0.12065 -0.2794)
			(stroke
				(width 0.1)
				(type default)
			)
			(layer "F.Fab")
		)
		(fp_line
			(start -0.12065 0.2794)
			(end -0.12065 0.3048)
			(stroke
				(width 0.1)
				(type default)
			)
			(layer "F.Fab")
		)
		(fp_line
			(start -0.12065 0.3048)
			(end -0.67945 0.3048)
			(stroke
				(width 0.1)
				(type default)
			)
			(layer "F.Fab")
		)
		(fp_line
			(start 0.120396 0.2794)
			(end -0.12065 0.2794)
			(stroke
				(width 0.1)
				(type default)
			)
			(layer "F.Fab")
		)
		(fp_line
			(start 0.120396 0.3048)
			(end 0.120396 0.2794)
			(stroke
				(width 0.1)
				(type default)
			)
			(layer "F.Fab")
		)
		(fp_line
			(start 0.12065 -0.3048)
			(end 0.67945 -0.3048)
			(stroke
				(width 0.1)
				(type default)
			)
			(layer "F.Fab")
		)
		(fp_line
			(start 0.12065 -0.2794)
			(end 0.12065 -0.3048)
			(stroke
				(width 0.1)
				(type default)
			)
			(layer "F.Fab")
		)
		(fp_line
			(start 0.67945 -0.3048)
			(end 0.67945 0.3048)
			(stroke
				(width 0.1)
				(type default)
			)
			(layer "F.Fab")
		)
		(fp_line
			(start 0.67945 0.3048)
			(end 0.120396 0.3048)
			(stroke
				(width 0.1)
				(type default)
			)
			(layer "F.Fab")
		)
		(pad "1" smd circle
			(at -0.40005 0)
			(size 0 0)
			(layers "F.Cu" "F.Mask" "F.Paste")
			(net "SMB_CLK_ISO_R_SCL_R1")
		)
		(pad "2" smd circle
			(at 0.40005 0)
			(size 0 0)
			(layers "F.Cu" "F.Mask" "F.Paste")
			(net "P3V3")
		)
	)
	(footprint ""
		(layer "F.Cu")
		(at 71.588122 -343.952322 90)
		(property "Reference" "C120"
			(at 0 0 90)
			(layer "F.SilkS")
			(hide yes)
			(effects
				(font
					(size 1.27 1.27)
				)
			)
		)
		(property "Value" ""
			(at 0 0 90)
			(layer "F.Fab")
			(effects
				(font
					(size 1.27 1.27)
				)
			)
		)
		(duplicate_pad_numbers_are_jumpers no)
		(fp_line
			(start 0.299974 -0.150114)
			(end 0.299974 0.150114)
			(stroke
				(width 0.1)
				(type default)
			)
			(layer "F.Fab")
		)
		(fp_line
			(start -0.299974 -0.150114)
			(end 0.299974 -0.150114)
			(stroke
				(width 0.1)
				(type default)
			)
			(layer "F.Fab")
		)
		(fp_line
			(start 0.299974 0.150114)
			(end -0.299974 0.150114)
			(stroke
				(width 0.1)
				(type default)
			)
			(layer "F.Fab")
		)
		(fp_line
			(start -0.299974 0.150114)
			(end -0.299974 -0.150114)
			(stroke
				(width 0.1)
				(type default)
			)
			(layer "F.Fab")
		)
		(pad "1" smd rect
			(at -0.2667 0 90)
			(size 0.3048 0.381)
			(layers "F.Cu" "F.Mask" "F.Paste")
			(net "P5E_PEX0_STN5_TX_DN<84>")
		)
		(pad "2" smd rect
			(at 0.2667 0 90)
			(size 0.3048 0.381)
			(layers "F.Cu" "F.Mask" "F.Paste")
			(net "P5E_PEX0_STN5_TX_C_DN<84>")
		)
	)
	(footprint ""
		(layer "F.Cu")
		(at 37.960808 -350.098614 90)
		(property "Reference" "C174"
			(at 0 0 90)
			(layer "F.SilkS")
			(hide yes)
			(effects
				(font
					(size 1.27 1.27)
				)
			)
		)
		(property "Value" ""
			(at 0 0 90)
			(layer "F.Fab")
			(effects
				(font
					(size 1.27 1.27)
				)
			)
		)
		(duplicate_pad_numbers_are_jumpers no)
		(fp_line
			(start 0.299974 -0.150114)
			(end 0.299974 0.150114)
			(stroke
				(width 0.1)
				(type default)
			)
			(layer "F.Fab")
		)
		(fp_line
			(start -0.299974 -0.150114)
			(end 0.299974 -0.150114)
			(stroke
				(width 0.1)
				(type default)
			)
			(layer "F.Fab")
		)
		(fp_line
			(start 0.299974 0.150114)
			(end -0.299974 0.150114)
			(stroke
				(width 0.1)
				(type default)
			)
			(layer "F.Fab")
		)
		(fp_line
			(start -0.299974 0.150114)
			(end -0.299974 -0.150114)
			(stroke
				(width 0.1)
				(type default)
			)
			(layer "F.Fab")
		)
		(pad "1" smd rect
			(at -0.2667 0 90)
			(size 0.3048 0.381)
			(layers "F.Cu" "F.Mask" "F.Paste")
			(net "P5E_PEX0_STN7_TX_DN<121>")
		)
		(pad "2" smd rect
			(at 0.2667 0 90)
			(size 0.3048 0.381)
			(layers "F.Cu" "F.Mask" "F.Paste")
			(net "P5E_PEX0_STN7_TX_C_DN<121>")
		)
	)
	(footprint ""
		(layer "F.Cu")
		(at 356.239318 -205.160118 90)
		(property "Reference" "R6419"
			(at 0 0 90)
			(layer "F.SilkS")
			(hide yes)
			(effects
				(font
					(size 1.27 1.27)
				)
			)
		)
		(property "Value" ""
			(at 0 0 90)
			(layer "F.Fab")
			(effects
				(font
					(size 1.27 1.27)
				)
			)
		)
		(duplicate_pad_numbers_are_jumpers no)
		(fp_line
			(start 0.7874 -0.4064)
			(end 0.7874 0.4064)
			(stroke
				(width 0.1524)
				(type default)
			)
			(layer "F.SilkS")
		)
		(fp_line
			(start -0.7874 -0.4064)
			(end 0.7874 -0.4064)
			(stroke
				(width 0.1524)
				(type default)
			)
			(layer "F.SilkS")
		)
		(fp_line
			(start 0.7874 0.4064)
			(end -0.7874 0.4064)
			(stroke
				(width 0.1524)
				(type default)
			)
			(layer "F.SilkS")
		)
		(fp_line
			(start -0.7874 0.4064)
			(end -0.7874 -0.4064)
			(stroke
				(width 0.1524)
				(type default)
			)
			(layer "F.SilkS")
		)
		(fp_line
			(start -0.12065 -0.305054)
			(end -0.12065 -0.2794)
			(stroke
				(width 0.1)
				(type default)
			)
			(layer "F.Fab")
		)
		(fp_line
			(start -0.67945 -0.305054)
			(end -0.12065 -0.305054)
			(stroke
				(width 0.1)
				(type default)
			)
			(layer "F.Fab")
		)
		(fp_line
			(start 0.67945 -0.3048)
			(end 0.67945 0.3048)
			(stroke
				(width 0.1)
				(type default)
			)
			(layer "F.Fab")
		)
		(fp_line
			(start 0.12065 -0.3048)
			(end 0.67945 -0.3048)
			(stroke
				(width 0.1)
				(type default)
			)
			(layer "F.Fab")
		)
		(fp_line
			(start 0.12065 -0.2794)
			(end 0.12065 -0.3048)
			(stroke
				(width 0.1)
				(type default)
			)
			(layer "F.Fab")
		)
		(fp_line
			(start -0.12065 -0.2794)
			(end 0.12065 -0.2794)
			(stroke
				(width 0.1)
				(type default)
			)
			(layer "F.Fab")
		)
		(fp_line
			(start 0.120396 0.2794)
			(end -0.12065 0.2794)
			(stroke
				(width 0.1)
				(type default)
			)
			(layer "F.Fab")
		)
		(fp_line
			(start -0.12065 0.2794)
			(end -0.12065 0.3048)
			(stroke
				(width 0.1)
				(type default)
			)
			(layer "F.Fab")
		)
		(fp_line
			(start 0.67945 0.3048)
			(end 0.120396 0.3048)
			(stroke
				(width 0.1)
				(type default)
			)
			(layer "F.Fab")
		)
		(fp_line
			(start 0.120396 0.3048)
			(end 0.120396 0.2794)
			(stroke
				(width 0.1)
				(type default)
			)
			(layer "F.Fab")
		)
		(fp_line
			(start -0.12065 0.3048)
			(end -0.67945 0.3048)
			(stroke
				(width 0.1)
				(type default)
			)
			(layer "F.Fab")
		)
		(fp_line
			(start -0.67945 0.3048)
			(end -0.67945 -0.305054)
			(stroke
				(width 0.1)
				(type default)
			)
			(layer "F.Fab")
		)
		(pad "1" smd circle
			(at -0.40005 0 90)
			(size 0 0)
			(layers "F.Cu" "F.Mask" "F.Paste")
			(net "FPGA_PEX1_MODE_SEL1_R")
		)
		(pad "2" smd circle
			(at 0.40005 0 90)
			(size 0 0)
			(layers "F.Cu" "F.Mask" "F.Paste")
			(net "FPGA_PEX1_MODE_SEL1")
		)
	)
	(footprint ""
		(layer "F.Cu")
		(at 381.254 -194.31)
		(property "Reference" "R4694"
			(at 0 0 0)
			(layer "F.SilkS")
			(hide yes)
			(effects
				(font
					(size 1.27 1.27)
				)
			)
		)
		(property "Value" ""
			(at 0 0 0)
			(layer "F.Fab")
			(effects
				(font
					(size 1.27 1.27)
				)
			)
		)
		(duplicate_pad_numbers_are_jumpers no)
		(fp_line
			(start -0.7874 -0.4064)
			(end 0.7874 -0.4064)
			(stroke
				(width 0.1524)
				(type default)
			)
			(layer "F.SilkS")
		)
		(fp_line
			(start -0.7874 0.4064)
			(end -0.7874 -0.4064)
			(stroke
				(width 0.1524)
				(type default)
			)
			(layer "F.SilkS")
		)
		(fp_line
			(start 0.7874 -0.4064)
			(end 0.7874 0.4064)
			(stroke
				(width 0.1524)
				(type default)
			)
			(layer "F.SilkS")
		)
		(fp_line
			(start 0.7874 0.4064)
			(end -0.7874 0.4064)
			(stroke
				(width 0.1524)
				(type default)
			)
			(layer "F.SilkS")
		)
		(fp_line
			(start -0.67945 -0.305054)
			(end -0.12065 -0.305054)
			(stroke
				(width 0.1)
				(type default)
			)
			(layer "F.Fab")
		)
		(fp_line
			(start -0.67945 0.3048)
			(end -0.67945 -0.305054)
			(stroke
				(width 0.1)
				(type default)
			)
			(layer "F.Fab")
		)
		(fp_line
			(start -0.12065 -0.305054)
			(end -0.12065 -0.2794)
			(stroke
				(width 0.1)
				(type default)
			)
			(layer "F.Fab")
		)
		(fp_line
			(start -0.12065 -0.2794)
			(end 0.12065 -0.2794)
			(stroke
				(width 0.1)
				(type default)
			)
			(layer "F.Fab")
		)
		(fp_line
			(start -0.12065 0.2794)
			(end -0.12065 0.3048)
			(stroke
				(width 0.1)
				(type default)
			)
			(layer "F.Fab")
		)
		(fp_line
			(start -0.12065 0.3048)
			(end -0.67945 0.3048)
			(stroke
				(width 0.1)
				(type default)
			)
			(layer "F.Fab")
		)
		(fp_line
			(start 0.120396 0.2794)
			(end -0.12065 0.2794)
			(stroke
				(width 0.1)
				(type default)
			)
			(layer "F.Fab")
		)
		(fp_line
			(start 0.120396 0.3048)
			(end 0.120396 0.2794)
			(stroke
				(width 0.1)
				(type default)
			)
			(layer "F.Fab")
		)
		(fp_line
			(start 0.12065 -0.3048)
			(end 0.67945 -0.3048)
			(stroke
				(width 0.1)
				(type default)
			)
			(layer "F.Fab")
		)
		(fp_line
			(start 0.12065 -0.2794)
			(end 0.12065 -0.3048)
			(stroke
				(width 0.1)
				(type default)
			)
			(layer "F.Fab")
		)
		(fp_line
			(start 0.67945 -0.3048)
			(end 0.67945 0.3048)
			(stroke
				(width 0.1)
				(type default)
			)
			(layer "F.Fab")
		)
		(fp_line
			(start 0.67945 0.3048)
			(end 0.120396 0.3048)
			(stroke
				(width 0.1)
				(type default)
			)
			(layer "F.Fab")
		)
		(pad "1" smd circle
			(at -0.40005 0)
			(size 0 0)
			(layers "F.Cu" "F.Mask" "F.Paste")
			(net "PRSNT_NIC2_FPGA_PCA9555_N")
		)
		(pad "2" smd circle
			(at 0.40005 0)
			(size 0 0)
			(layers "F.Cu" "F.Mask" "F.Paste")
			(net "PRSNT_NIC2_FPGA_R_N")
		)
	)
	(footprint ""
		(layer "F.Cu")
		(at 207.983074 -212.913214 90)
		(property "Reference" "R4892"
			(at 0 0 90)
			(layer "F.SilkS")
			(hide yes)
			(effects
				(font
					(size 1.27 1.27)
				)
			)
		)
		(property "Value" ""
			(at 0 0 90)
			(layer "F.Fab")
			(effects
				(font
					(size 1.27 1.27)
				)
			)
		)
		(duplicate_pad_numbers_are_jumpers no)
		(fp_line
			(start 0.7874 -0.4064)
			(end 0.7874 0.4064)
			(stroke
				(width 0.1524)
				(type default)
			)
			(layer "F.SilkS")
		)
		(fp_line
			(start -0.7874 -0.4064)
			(end 0.7874 -0.4064)
			(stroke
				(width 0.1524)
				(type default)
			)
			(layer "F.SilkS")
		)
		(fp_line
			(start 0.7874 0.4064)
			(end -0.7874 0.4064)
			(stroke
				(width 0.1524)
				(type default)
			)
			(layer "F.SilkS")
		)
		(fp_line
			(start -0.7874 0.4064)
			(end -0.7874 -0.4064)
			(stroke
				(width 0.1524)
				(type default)
			)
			(layer "F.SilkS")
		)
		(fp_line
			(start -0.12065 -0.305054)
			(end -0.12065 -0.2794)
			(stroke
				(width 0.1)
				(type default)
			)
			(layer "F.Fab")
		)
		(fp_line
			(start -0.67945 -0.305054)
			(end -0.12065 -0.305054)
			(stroke
				(width 0.1)
				(type default)
			)
			(layer "F.Fab")
		)
		(fp_line
			(start 0.67945 -0.3048)
			(end 0.67945 0.3048)
			(stroke
				(width 0.1)
				(type default)
			)
			(layer "F.Fab")
		)
		(fp_line
			(start 0.12065 -0.3048)
			(end 0.67945 -0.3048)
			(stroke
				(width 0.1)
				(type default)
			)
			(layer "F.Fab")
		)
		(fp_line
			(start 0.12065 -0.2794)
			(end 0.12065 -0.3048)
			(stroke
				(width 0.1)
				(type default)
			)
			(layer "F.Fab")
		)
		(fp_line
			(start -0.12065 -0.2794)
			(end 0.12065 -0.2794)
			(stroke
				(width 0.1)
				(type default)
			)
			(layer "F.Fab")
		)
		(fp_line
			(start 0.120396 0.2794)
			(end -0.12065 0.2794)
			(stroke
				(width 0.1)
				(type default)
			)
			(layer "F.Fab")
		)
		(fp_line
			(start -0.12065 0.2794)
			(end -0.12065 0.3048)
			(stroke
				(width 0.1)
				(type default)
			)
			(layer "F.Fab")
		)
		(fp_line
			(start 0.67945 0.3048)
			(end 0.120396 0.3048)
			(stroke
				(width 0.1)
				(type default)
			)
			(layer "F.Fab")
		)
		(fp_line
			(start 0.120396 0.3048)
			(end 0.120396 0.2794)
			(stroke
				(width 0.1)
				(type default)
			)
			(layer "F.Fab")
		)
		(fp_line
			(start -0.12065 0.3048)
			(end -0.67945 0.3048)
			(stroke
				(width 0.1)
				(type default)
			)
			(layer "F.Fab")
		)
		(fp_line
			(start -0.67945 0.3048)
			(end -0.67945 -0.305054)
			(stroke
				(width 0.1)
				(type default)
			)
			(layer "F.Fab")
		)
		(pad "1" smd circle
			(at -0.40005 0 90)
			(size 0 0)
			(layers "F.Cu" "F.Mask" "F.Paste")
			(net "UART_BIC_DEBUG_R_RX")
		)
		(pad "2" smd circle
			(at 0.40005 0 90)
			(size 0 0)
			(layers "F.Cu" "F.Mask" "F.Paste")
			(net "UART_BIC_DEBUG_RX")
		)
	)
	(footprint ""
		(layer "F.Cu")
		(at 49.656492 -17.419574 180)
		(property "Reference" "R1635"
			(at 0 0 180)
			(layer "F.SilkS")
			(hide yes)
			(effects
				(font
					(size 1.27 1.27)
				)
			)
		)
		(property "Value" ""
			(at 0 0 180)
			(layer "F.Fab")
			(effects
				(font
					(size 1.27 1.27)
				)
			)
		)
		(duplicate_pad_numbers_are_jumpers no)
		(fp_line
			(start 0.7874 0.4064)
			(end -0.7874 0.4064)
			(stroke
				(width 0.1524)
				(type default)
			)
			(layer "F.SilkS")
		)
		(fp_line
			(start 0.7874 -0.4064)
			(end 0.7874 0.4064)
			(stroke
				(width 0.1524)
				(type default)
			)
			(layer "F.SilkS")
		)
		(fp_line
			(start -0.7874 0.4064)
			(end -0.7874 -0.4064)
			(stroke
				(width 0.1524)
				(type default)
			)
			(layer "F.SilkS")
		)
		(fp_line
			(start -0.7874 -0.4064)
			(end 0.7874 -0.4064)
			(stroke
				(width 0.1524)
				(type default)
			)
			(layer "F.SilkS")
		)
		(fp_line
			(start 0.67945 0.3048)
			(end 0.120396 0.3048)
			(stroke
				(width 0.1)
				(type default)
			)
			(layer "F.Fab")
		)
		(fp_line
			(start 0.67945 -0.3048)
			(end 0.67945 0.3048)
			(stroke
				(width 0.1)
				(type default)
			)
			(layer "F.Fab")
		)
		(fp_line
			(start 0.12065 -0.2794)
			(end 0.12065 -0.3048)
			(stroke
				(width 0.1)
				(type default)
			)
			(layer "F.Fab")
		)
		(fp_line
			(start 0.12065 -0.3048)
			(end 0.67945 -0.3048)
			(stroke
				(width 0.1)
				(type default)
			)
			(layer "F.Fab")
		)
		(fp_line
			(start 0.120396 0.3048)
			(end 0.120396 0.2794)
			(stroke
				(width 0.1)
				(type default)
			)
			(layer "F.Fab")
		)
		(fp_line
			(start 0.120396 0.2794)
			(end -0.12065 0.2794)
			(stroke
				(width 0.1)
				(type default)
			)
			(layer "F.Fab")
		)
		(fp_line
			(start -0.12065 0.3048)
			(end -0.67945 0.3048)
			(stroke
				(width 0.1)
				(type default)
			)
			(layer "F.Fab")
		)
		(fp_line
			(start -0.12065 0.2794)
			(end -0.12065 0.3048)
			(stroke
				(width 0.1)
				(type default)
			)
			(layer "F.Fab")
		)
		(fp_line
			(start -0.12065 -0.2794)
			(end 0.12065 -0.2794)
			(stroke
				(width 0.1)
				(type default)
			)
			(layer "F.Fab")
		)
		(fp_line
			(start -0.12065 -0.305054)
			(end -0.12065 -0.2794)
			(stroke
				(width 0.1)
				(type default)
			)
			(layer "F.Fab")
		)
		(fp_line
			(start -0.67945 0.3048)
			(end -0.67945 -0.305054)
			(stroke
				(width 0.1)
				(type default)
			)
			(layer "F.Fab")
		)
		(fp_line
			(start -0.67945 -0.305054)
			(end -0.12065 -0.305054)
			(stroke
				(width 0.1)
				(type default)
			)
			(layer "F.Fab")
		)
		(pad "1" smd circle
			(at -0.40005 0 180)
			(size 0 0)
			(layers "F.Cu" "F.Mask" "F.Paste")
			(net "P3V3_SSD1")
		)
		(pad "2" smd circle
			(at 0.40005 0 180)
			(size 0 0)
			(layers "F.Cu" "F.Mask" "F.Paste")
			(net "SMB_ISO_SSD1_SCL")
		)
	)
)
